# SCM (Grand Teton) — schematic netlist excerpt (pin names and nets, part order shuffled) for the footprints in the layout excerpt that follows; sources: Cadence DE-HDL packaged netlist, KiCad conversion of 12092022_DA0F0TMDCD0_F0T_Management_Board_D_brd_V3_OCP.brd

R810  Q_RES  10K 1% CHIP  pkg 0402LF  page 34 : A = PU_FPGA_NSTATUS ; B = PVCCIO_AUX_PLD
PC216  Q_CAP  0.22UF 16V 10% X7R  pkg 0402  page 51 : A = SW_P5V_AUX_BST ; B = SW_P5V_AUX_SW

(kicad_pcb
	(version 20260206)
	(generator "pcbnew")
	(generator_version "10.0")
	(general
		(thickness 1.6)
		(legacy_teardrops no)
	)
	(paper "A4")
	(title_block
		(title "12092022_DA0F0TMDCD0_F0T_Management_Board_D_brd_V3_OCP.brd")
		(comment 1 "Grand Teton / footprints 158-159 of 1440")
	)
	(layers
		(0 "F.Cu" signal "TOP")
		(4 "In1.Cu" signal "GND")
		(6 "In2.Cu" signal "IN1")
		(8 "In3.Cu" signal "GND1")
		(10 "In4.Cu" signal "IN2")
		(12 "In5.Cu" signal "VCC")
		(14 "In6.Cu" signal "VCC1")
		(16 "In7.Cu" signal "IN3")
		(18 "In8.Cu" signal "GND2")
		(20 "In9.Cu" signal "IN4")
		(22 "In10.Cu" signal "GND3")
		(2 "B.Cu" signal "BOTTOM")
		(9 "F.Adhes" user "F.Adhesive")
		(11 "B.Adhes" user "B.Adhesive")
		(13 "F.Paste" user "Package Geometry/Pastemask Top")
		(15 "B.Paste" user "Package Geometry/Pastemask Bottom")
		(5 "F.SilkS" user "Ref Des/Silkscreen Top")
		(7 "B.SilkS" user "Ref Des/Silkscreen Bottom")
		(1 "F.Mask" user "Board Geometry/Soldermask Top")
		(3 "B.Mask" user "Board Geometry/Soldermask Bottom")
		(17 "Dwgs.User" user "User.Drawings")
		(19 "Cmts.User" user "User.Comments")
		(21 "Eco1.User" user "User.Eco1")
		(23 "Eco2.User" user "User.Eco2")
		(25 "Edge.Cuts" user "Board Geometry/Outline")
		(27 "Margin" user)
		(31 "F.CrtYd" user "Package Geometry/Place Bound Top")
		(29 "B.CrtYd" user "Package Geometry/Place Bound Bottom")
		(35 "F.Fab" user "Ref Des/Assembly Top")
		(33 "B.Fab" user "Ref Des/Assembly Bottom")
	)
	(footprint ""
		(layer "F.Cu")
		(at 9.842246 -46.814994)
		(property "Reference" "PC216"
			(at 0 0 0)
			(layer "F.SilkS")
			(hide yes)
			(effects
				(font
					(size 1.27 1.27)
				)
			)
		)
		(property "Value" ""
			(at 0 0 0)
			(layer "F.Fab")
			(effects
				(font
					(size 1.27 1.27)
				)
			)
		)
		(duplicate_pad_numbers_are_jumpers no)
		(fp_line
			(start -0.7874 -0.4064)
			(end 0.7874 -0.4064)
			(stroke
				(width 0.1524)
				(type default)
			)
			(layer "F.SilkS")
		)
		(fp_line
			(start -0.7874 0.4064)
			(end -0.7874 -0.4064)
			(stroke
				(width 0.1524)
				(type default)
			)
			(layer "F.SilkS")
		)
		(fp_line
			(start 0.7874 -0.4064)
			(end 0.7874 0.4064)
			(stroke
				(width 0.1524)
				(type default)
			)
			(layer "F.SilkS")
		)
		(fp_line
			(start 0.7874 0.4064)
			(end -0.7874 0.4064)
			(stroke
				(width 0.1524)
				(type default)
			)
			(layer "F.SilkS")
		)
		(fp_line
			(start -0.67945 -0.305054)
			(end -0.12065 -0.305054)
			(stroke
				(width 0.1)
				(type default)
			)
			(layer "F.Fab")
		)
		(fp_line
			(start -0.67945 0.3048)
			(end -0.67945 -0.305054)
			(stroke
				(width 0.1)
				(type default)
			)
			(layer "F.Fab")
		)
		(fp_line
			(start -0.12065 -0.305054)
			(end -0.12065 -0.2794)
			(stroke
				(width 0.1)
				(type default)
			)
			(layer "F.Fab")
		)
		(fp_line
			(start -0.12065 -0.2794)
			(end 0.12065 -0.2794)
			(stroke
				(width 0.1)
				(type default)
			)
			(layer "F.Fab")
		)
		(fp_line
			(start -0.12065 0.2794)
			(end -0.12065 0.3048)
			(stroke
				(width 0.1)
				(type default)
			)
			(layer "F.Fab")
		)
		(fp_line
			(start -0.12065 0.3048)
			(end -0.67945 0.3048)
			(stroke
				(width 0.1)
				(type default)
			)
			(layer "F.Fab")
		)
		(fp_line
			(start 0.120396 0.2794)
			(end -0.12065 0.2794)
			(stroke
				(width 0.1)
				(type default)
			)
			(layer "F.Fab")
		)
		(fp_line
			(start 0.120396 0.3048)
			(end 0.120396 0.2794)
			(stroke
				(width 0.1)
				(type default)
			)
			(layer "F.Fab")
		)
		(fp_line
			(start 0.12065 -0.3048)
			(end 0.67945 -0.3048)
			(stroke
				(width 0.1)
				(type default)
			)
			(layer "F.Fab")
		)
		(fp_line
			(start 0.12065 -0.2794)
			(end 0.12065 -0.3048)
			(stroke
				(width 0.1)
				(type default)
			)
			(layer "F.Fab")
		)
		(fp_line
			(start 0.67945 -0.3048)
			(end 0.67945 0.3048)
			(stroke
				(width 0.1)
				(type default)
			)
			(layer "F.Fab")
		)
		(fp_line
			(start 0.67945 0.3048)
			(end 0.120396 0.3048)
			(stroke
				(width 0.1)
				(type default)
			)
			(layer "F.Fab")
		)
		(pad "1" smd circle
			(at -0.40005 0)
			(size 0 0)
			(layers "F.Cu" "F.Mask" "F.Paste")
			(net "SW_P5V_AUX_BST")
		)
		(pad "2" smd circle
			(at 0.40005 0)
			(size 0 0)
			(layers "F.Cu" "F.Mask" "F.Paste")
			(net "SW_P5V_AUX_SW")
		)
	)
	(footprint ""
		(layer "F.Cu")
		(at 15.494 -83.693 -90)
		(property "Reference" "R810"
			(at 0 0 270)
			(layer "F.SilkS")
			(hide yes)
			(effects
				(font
					(size 1.27 1.27)
				)
			)
		)
		(property "Value" ""
			(at 0 0 270)
			(layer "F.Fab")
			(effects
				(font
					(size 1.27 1.27)
				)
			)
		)
		(duplicate_pad_numbers_are_jumpers no)
		(fp_line
			(start -0.7874 0.4064)
			(end -0.7874 -0.4064)
			(stroke
				(width 0.1524)
				(type default)
			)
			(layer "F.SilkS")
		)
		(fp_line
			(start 0.7874 0.4064)
			(end -0.7874 0.4064)
			(stroke
				(width 0.1524)
				(type default)
			)
			(layer "F.SilkS")
		)
		(fp_line
			(start -0.7874 -0.4064)
			(end 0.7874 -0.4064)
			(stroke
				(width 0.1524)
				(type default)
			)
			(layer "F.SilkS")
		)
		(fp_line
			(start 0.7874 -0.4064)
			(end 0.7874 0.4064)
			(stroke
				(width 0.1524)
				(type default)
			)
			(layer "F.SilkS")
		)
		(fp_line
			(start -0.67945 0.3048)
			(end -0.67945 -0.305054)
			(stroke
				(width 0.1)
				(type default)
			)
			(layer "F.Fab")
		)
		(fp_line
			(start -0.12065 0.3048)
			(end -0.67945 0.3048)
			(stroke
				(width 0.1)
				(type default)
			)
			(layer "F.Fab")
		)
		(fp_line
			(start 0.120396 0.3048)
			(end 0.120396 0.2794)
			(stroke
				(width 0.1)
				(type default)
			)
			(layer "F.Fab")
		)
		(fp_line
			(start 0.67945 0.3048)
			(end 0.120396 0.3048)
			(stroke
				(width 0.1)
				(type default)
			)
			(layer "F.Fab")
		)
		(fp_line
			(start -0.12065 0.2794)
			(end -0.12065 0.3048)
			(stroke
				(width 0.1)
				(type default)
			)
			(layer "F.Fab")
		)
		(fp_line
			(start 0.120396 0.2794)
			(end -0.12065 0.2794)
			(stroke
				(width 0.1)
				(type default)
			)
			(layer "F.Fab")
		)
		(fp_line
			(start -0.12065 -0.2794)
			(end 0.12065 -0.2794)
			(stroke
				(width 0.1)
				(type default)
			)
			(layer "F.Fab")
		)
		(fp_line
			(start 0.12065 -0.2794)
			(end 0.12065 -0.3048)
			(stroke
				(width 0.1)
				(type default)
			)
			(layer "F.Fab")
		)
		(fp_line
			(start 0.12065 -0.3048)
			(end 0.67945 -0.3048)
			(stroke
				(width 0.1)
				(type default)
			)
			(layer "F.Fab")
		)
		(fp_line
			(start 0.67945 -0.3048)
			(end 0.67945 0.3048)
			(stroke
				(width 0.1)
				(type default)
			)
			(layer "F.Fab")
		)
		(fp_line
			(start -0.67945 -0.305054)
			(end -0.12065 -0.305054)
			(stroke
				(width 0.1)
				(type default)
			)
			(layer "F.Fab")
		)
		(fp_line
			(start -0.12065 -0.305054)
			(end -0.12065 -0.2794)
			(stroke
				(width 0.1)
				(type default)
			)
			(layer "F.Fab")
		)
		(pad "1" smd circle
			(at -0.40005 0 270)
			(size 0 0)
			(layers "F.Cu" "F.Mask" "F.Paste")
			(net "PU_FPGA_NSTATUS")
		)
		(pad "2" smd circle
			(at 0.40005 0 270)
			(size 0 0)
			(layers "F.Cu" "F.Mask" "F.Paste")
			(net "PVCCIO_AUX_PLD")
		)
	)
)
